(kicad_pcb
	(version 20260206)
	(generator "pcbnew")
	(generator_version "10.0")
	(general
		(thickness 1.6)
		(legacy_teardrops no)
	)
	(paper "A4")
	(title_block
		(title "03242023_DA0F0TMBIJ0_F0T_Motherboard_J_brd_V01_OCP.brd")
		(comment 1 "Grand Teton / footprints 1162-1168 of 6105")
	)
	(layers
		(0 "F.Cu" signal "TOP")
		(4 "In1.Cu" signal "GND")
		(6 "In2.Cu" signal "IN1")
		(8 "In3.Cu" signal "GND1")
		(10 "In4.Cu" signal "IN2")
		(12 "In5.Cu" signal "GND2")
		(14 "In6.Cu" signal "IN3")
		(16 "In7.Cu" signal "GND3")
		(18 "In8.Cu" signal "VCC")
		(20 "In9.Cu" signal "VCC1")
		(22 "In10.Cu" signal "GND4")
		(24 "In11.Cu" signal "IN4")
		(26 "In12.Cu" signal "GND5")
		(28 "In13.Cu" signal "IN5")
		(30 "In14.Cu" signal "GND6")
		(32 "In15.Cu" signal "IN6")
		(34 "In16.Cu" signal "GND7")
		(2 "B.Cu" signal "BOTTOM")
		(9 "F.Adhes" user "F.Adhesive")
		(11 "B.Adhes" user "B.Adhesive")
		(13 "F.Paste" user "Package Geometry/Pastemask Top")
		(15 "B.Paste" user "Package Geometry/Pastemask Bottom")
		(5 "F.SilkS" user "Ref Des/Silkscreen Top")
		(7 "B.SilkS" user "Ref Des/Silkscreen Bottom")
		(1 "F.Mask" user "Board Geometry/Soldermask Top")
		(3 "B.Mask" user "Board Geometry/Soldermask Bottom")
		(17 "Dwgs.User" user "User.Drawings")
		(19 "Cmts.User" user "User.Comments")
		(21 "Eco1.User" user "User.Eco1")
		(23 "Eco2.User" user "User.Eco2")
		(25 "Edge.Cuts" user "Board Geometry/Outline")
		(27 "Margin" user)
		(31 "F.CrtYd" user "Package Geometry/Place Bound Top")
		(29 "B.CrtYd" user "Package Geometry/Place Bound Bottom")
		(35 "F.Fab" user "Ref Des/Assembly Top")
		(33 "B.Fab" user "Ref Des/Assembly Bottom")
	)
	(footprint ""
		(layer "F.Cu")
		(at 120.37822 -422.463468 180)
		(property "Reference" "R2912"
			(at 0 0 180)
			(layer "F.SilkS")
			(hide yes)
			(effects
				(font
					(size 1.27 1.27)
				)
			)
		)
		(property "Value" ""
			(at 0 0 180)
			(layer "F.Fab")
			(effects
				(font
					(size 1.27 1.27)
				)
			)
		)
		(duplicate_pad_numbers_are_jumpers no)
		(fp_line
			(start 0.7874 0.4064)
			(end -0.7874 0.4064)
			(stroke
				(width 0.1524)
				(type default)
			)
			(layer "F.SilkS")
		)
		(fp_line
			(start 0.7874 -0.4064)
			(end 0.7874 0.4064)
			(stroke
				(width 0.1524)
				(type default)
			)
			(layer "F.SilkS")
		)
		(fp_line
			(start -0.7874 0.4064)
			(end -0.7874 -0.4064)
			(stroke
				(width 0.1524)
				(type default)
			)
			(layer "F.SilkS")
		)
		(fp_line
			(start -0.7874 -0.4064)
			(end 0.7874 -0.4064)
			(stroke
				(width 0.1524)
				(type default)
			)
			(layer "F.SilkS")
		)
		(fp_line
			(start 0.67945 0.3048)
			(end 0.120396 0.3048)
			(stroke
				(width 0.1)
				(type default)
			)
			(layer "F.Fab")
		)
		(fp_line
			(start 0.67945 -0.3048)
			(end 0.67945 0.3048)
			(stroke
				(width 0.1)
				(type default)
			)
			(layer "F.Fab")
		)
		(fp_line
			(start 0.12065 -0.2794)
			(end 0.12065 -0.3048)
			(stroke
				(width 0.1)
				(type default)
			)
			(layer "F.Fab")
		)
		(fp_line
			(start 0.12065 -0.3048)
			(end 0.67945 -0.3048)
			(stroke
				(width 0.1)
				(type default)
			)
			(layer "F.Fab")
		)
		(fp_line
			(start 0.120396 0.3048)
			(end 0.120396 0.2794)
			(stroke
				(width 0.1)
				(type default)
			)
			(layer "F.Fab")
		)
		(fp_line
			(start 0.120396 0.2794)
			(end -0.12065 0.2794)
			(stroke
				(width 0.1)
				(type default)
			)
			(layer "F.Fab")
		)
		(fp_line
			(start -0.12065 0.3048)
			(end -0.67945 0.3048)
			(stroke
				(width 0.1)
				(type default)
			)
			(layer "F.Fab")
		)
		(fp_line
			(start -0.12065 0.2794)
			(end -0.12065 0.3048)
			(stroke
				(width 0.1)
				(type default)
			)
			(layer "F.Fab")
		)
		(fp_line
			(start -0.12065 -0.2794)
			(end 0.12065 -0.2794)
			(stroke
				(width 0.1)
				(type default)
			)
			(layer "F.Fab")
		)
		(fp_line
			(start -0.12065 -0.305054)
			(end -0.12065 -0.2794)
			(stroke
				(width 0.1)
				(type default)
			)
			(layer "F.Fab")
		)
		(fp_line
			(start -0.67945 0.3048)
			(end -0.67945 -0.305054)
			(stroke
				(width 0.1)
				(type default)
			)
			(layer "F.Fab")
		)
		(fp_line
			(start -0.67945 -0.305054)
			(end -0.12065 -0.305054)
			(stroke
				(width 0.1)
				(type default)
			)
			(layer "F.Fab")
		)
		(pad "1" smd circle
			(at -0.40005 0 180)
			(size 0 0)
			(layers "F.Cu" "F.Mask" "F.Paste")
			(net "P3V3_AUX")
		)
		(pad "2" smd circle
			(at 0.40005 0 180)
			(size 0 0)
			(layers "F.Cu" "F.Mask" "F.Paste")
			(net "FM_GPU_PWR_EN_R1")
		)
	)
	(footprint ""
		(layer "F.Cu")
		(at 365.46663 -252.956314 -90)
		(property "Reference" "C1020"
			(at 0 0 270)
			(layer "F.SilkS")
			(hide yes)
			(effects
				(font
					(size 1.27 1.27)
				)
			)
		)
		(property "Value" ""
			(at 0 0 270)
			(layer "F.Fab")
			(effects
				(font
					(size 1.27 1.27)
				)
			)
		)
		(duplicate_pad_numbers_are_jumpers no)
		(fp_line
			(start -0.7874 0.4064)
			(end -0.7874 -0.4064)
			(stroke
				(width 0.1524)
				(type default)
			)
			(layer "F.SilkS")
		)
		(fp_line
			(start 0.7874 0.4064)
			(end -0.7874 0.4064)
			(stroke
				(width 0.1524)
				(type default)
			)
			(layer "F.SilkS")
		)
		(fp_line
			(start -0.7874 -0.4064)
			(end 0.7874 -0.4064)
			(stroke
				(width 0.1524)
				(type default)
			)
			(layer "F.SilkS")
		)
		(fp_line
			(start 0.7874 -0.4064)
			(end 0.7874 0.4064)
			(stroke
				(width 0.1524)
				(type default)
			)
			(layer "F.SilkS")
		)
		(fp_line
			(start -0.67945 0.3048)
			(end -0.67945 -0.305054)
			(stroke
				(width 0.1)
				(type default)
			)
			(layer "F.Fab")
		)
		(fp_line
			(start -0.12065 0.3048)
			(end -0.67945 0.3048)
			(stroke
				(width 0.1)
				(type default)
			)
			(layer "F.Fab")
		)
		(fp_line
			(start 0.120396 0.3048)
			(end 0.120396 0.2794)
			(stroke
				(width 0.1)
				(type default)
			)
			(layer "F.Fab")
		)
		(fp_line
			(start 0.67945 0.3048)
			(end 0.120396 0.3048)
			(stroke
				(width 0.1)
				(type default)
			)
			(layer "F.Fab")
		)
		(fp_line
			(start -0.12065 0.2794)
			(end -0.12065 0.3048)
			(stroke
				(width 0.1)
				(type default)
			)
			(layer "F.Fab")
		)
		(fp_line
			(start 0.120396 0.2794)
			(end -0.12065 0.2794)
			(stroke
				(width 0.1)
				(type default)
			)
			(layer "F.Fab")
		)
		(fp_line
			(start -0.12065 -0.2794)
			(end 0.12065 -0.2794)
			(stroke
				(width 0.1)
				(type default)
			)
			(layer "F.Fab")
		)
		(fp_line
			(start 0.12065 -0.2794)
			(end 0.12065 -0.3048)
			(stroke
				(width 0.1)
				(type default)
			)
			(layer "F.Fab")
		)
		(fp_line
			(start 0.12065 -0.3048)
			(end 0.67945 -0.3048)
			(stroke
				(width 0.1)
				(type default)
			)
			(layer "F.Fab")
		)
		(fp_line
			(start 0.67945 -0.3048)
			(end 0.67945 0.3048)
			(stroke
				(width 0.1)
				(type default)
			)
			(layer "F.Fab")
		)
		(fp_line
			(start -0.67945 -0.305054)
			(end -0.12065 -0.305054)
			(stroke
				(width 0.1)
				(type default)
			)
			(layer "F.Fab")
		)
		(fp_line
			(start -0.12065 -0.305054)
			(end -0.12065 -0.2794)
			(stroke
				(width 0.1)
				(type default)
			)
			(layer "F.Fab")
		)
		(pad "1" smd circle
			(at -0.40005 0 270)
			(size 0 0)
			(layers "F.Cu" "F.Mask" "F.Paste")
			(net "PVCCIN_CPU0")
		)
		(pad "2" smd circle
			(at 0.40005 0 270)
			(size 0 0)
			(layers "F.Cu" "F.Mask" "F.Paste")
			(net "GND")
		)
	)
	(footprint ""
		(layer "F.Cu")
		(at 152.755346 -115.4684 180)
		(property "Reference" "R4697"
			(at 0 0 180)
			(layer "F.SilkS")
			(hide yes)
			(effects
				(font
					(size 1.27 1.27)
				)
			)
		)
		(property "Value" ""
			(at 0 0 180)
			(layer "F.Fab")
			(effects
				(font
					(size 1.27 1.27)
				)
			)
		)
		(duplicate_pad_numbers_are_jumpers no)
		(fp_line
			(start 0.7874 0.4064)
			(end -0.7874 0.4064)
			(stroke
				(width 0.1524)
				(type default)
			)
			(layer "F.SilkS")
		)
		(fp_line
			(start 0.7874 -0.4064)
			(end 0.7874 0.4064)
			(stroke
				(width 0.1524)
				(type default)
			)
			(layer "F.SilkS")
		)
		(fp_line
			(start -0.7874 0.4064)
			(end -0.7874 -0.4064)
			(stroke
				(width 0.1524)
				(type default)
			)
			(layer "F.SilkS")
		)
		(fp_line
			(start -0.7874 -0.4064)
			(end 0.7874 -0.4064)
			(stroke
				(width 0.1524)
				(type default)
			)
			(layer "F.SilkS")
		)
		(fp_line
			(start 0.67945 0.3048)
			(end 0.120396 0.3048)
			(stroke
				(width 0.1)
				(type default)
			)
			(layer "F.Fab")
		)
		(fp_line
			(start 0.67945 -0.3048)
			(end 0.67945 0.3048)
			(stroke
				(width 0.1)
				(type default)
			)
			(layer "F.Fab")
		)
		(fp_line
			(start 0.12065 -0.2794)
			(end 0.12065 -0.3048)
			(stroke
				(width 0.1)
				(type default)
			)
			(layer "F.Fab")
		)
		(fp_line
			(start 0.12065 -0.3048)
			(end 0.67945 -0.3048)
			(stroke
				(width 0.1)
				(type default)
			)
			(layer "F.Fab")
		)
		(fp_line
			(start 0.120396 0.3048)
			(end 0.120396 0.2794)
			(stroke
				(width 0.1)
				(type default)
			)
			(layer "F.Fab")
		)
		(fp_line
			(start 0.120396 0.2794)
			(end -0.12065 0.2794)
			(stroke
				(width 0.1)
				(type default)
			)
			(layer "F.Fab")
		)
		(fp_line
			(start -0.12065 0.3048)
			(end -0.67945 0.3048)
			(stroke
				(width 0.1)
				(type default)
			)
			(layer "F.Fab")
		)
		(fp_line
			(start -0.12065 0.2794)
			(end -0.12065 0.3048)
			(stroke
				(width 0.1)
				(type default)
			)
			(layer "F.Fab")
		)
		(fp_line
			(start -0.12065 -0.2794)
			(end 0.12065 -0.2794)
			(stroke
				(width 0.1)
				(type default)
			)
			(layer "F.Fab")
		)
		(fp_line
			(start -0.12065 -0.305054)
			(end -0.12065 -0.2794)
			(stroke
				(width 0.1)
				(type default)
			)
			(layer "F.Fab")
		)
		(fp_line
			(start -0.67945 0.3048)
			(end -0.67945 -0.305054)
			(stroke
				(width 0.1)
				(type default)
			)
			(layer "F.Fab")
		)
		(fp_line
			(start -0.67945 -0.305054)
			(end -0.12065 -0.305054)
			(stroke
				(width 0.1)
				(type default)
			)
			(layer "F.Fab")
		)
		(pad "1" smd circle
			(at -0.40005 0 180)
			(size 0 0)
			(layers "F.Cu" "F.Mask" "F.Paste")
			(net "RST_SRST_PLD_BMC_R_N")
		)
		(pad "2" smd circle
			(at 0.40005 0 180)
			(size 0 0)
			(layers "F.Cu" "F.Mask" "F.Paste")
			(net "RST_SRST_PLD_BMC_N")
		)
	)
	(footprint ""
		(layer "F.Cu")
		(at 408.554682 -179.457858 180)
		(property "Reference" "PL5"
			(at 5.785104 -0.050292 0)
			(unlocked yes)
			(layer "F.SilkS")
			(effects
				(font
					(size 0.7874 0.5842)
					(thickness 0.1524)
				)
				(justify left)
			)
		)
		(property "Value" ""
			(at 0 0 180)
			(layer "F.Fab")
			(effects
				(font
					(size 1.27 1.27)
				)
			)
		)
		(duplicate_pad_numbers_are_jumpers no)
		(fp_line
			(start 3.24993 3.24993)
			(end -3.24993 3.24993)
			(stroke
				(width 0.1524)
				(type default)
			)
			(layer "F.SilkS")
		)
		(fp_line
			(start 3.24993 2.2352)
			(end 3.24993 3.24993)
			(stroke
				(width 0.1524)
				(type default)
			)
			(layer "F.SilkS")
		)
		(fp_line
			(start 3.24993 -3.24993)
			(end 3.24993 -2.2352)
			(stroke
				(width 0.1524)
				(type default)
			)
			(layer "F.SilkS")
		)
		(fp_line
			(start -3.24993 3.24993)
			(end -3.24993 2.2352)
			(stroke
				(width 0.1524)
				(type default)
			)
			(layer "F.SilkS")
		)
		(fp_line
			(start -3.24993 -2.2352)
			(end -3.24993 -3.24993)
			(stroke
				(width 0.1524)
				(type default)
			)
			(layer "F.SilkS")
		)
		(fp_line
			(start -3.24993 -3.24993)
			(end 3.24993 -3.24993)
			(stroke
				(width 0.1524)
				(type default)
			)
			(layer "F.SilkS")
		)
		(fp_line
			(start 3.24993 3.24993)
			(end -3.24993 3.24993)
			(stroke
				(width 0.1)
				(type default)
			)
			(layer "F.Fab")
		)
		(fp_line
			(start 3.24993 -3.24993)
			(end 3.24993 3.24993)
			(stroke
				(width 0.1)
				(type default)
			)
			(layer "F.Fab")
		)
		(fp_line
			(start -3.24993 3.24993)
			(end -3.24993 -3.24993)
			(stroke
				(width 0.1)
				(type default)
			)
			(layer "F.Fab")
		)
		(fp_line
			(start -3.24993 -3.24993)
			(end 3.24993 -3.24993)
			(stroke
				(width 0.1)
				(type default)
			)
			(layer "F.Fab")
		)
		(pad "1" smd rect
			(at -2.29997 0 180)
			(size 2.0066 4.2164)
			(layers "F.Cu" "F.Mask" "F.Paste")
			(net "SW_PVCCINFAON_CPU0_SW2")
		)
		(pad "2" smd rect
			(at 2.29997 0 180)
			(size 2.0066 4.2164)
			(layers "F.Cu" "F.Mask" "F.Paste")
			(net "PVCCINFAON_CPU0")
		)
	)
	(footprint ""
		(layer "F.Cu")
		(at 48.868838 -402.371052 -90)
		(property "Reference" "C711"
			(at 0 0 270)
			(layer "F.SilkS")
			(hide yes)
			(effects
				(font
					(size 1.27 1.27)
				)
			)
		)
		(property "Value" ""
			(at 0 0 270)
			(layer "F.Fab")
			(effects
				(font
					(size 1.27 1.27)
				)
			)
		)
		(duplicate_pad_numbers_are_jumpers no)
		(fp_line
			(start -0.299974 0.150114)
			(end -0.299974 -0.150114)
			(stroke
				(width 0.1)
				(type default)
			)
			(layer "F.Fab")
		)
		(fp_line
			(start 0.299974 0.150114)
			(end -0.299974 0.150114)
			(stroke
				(width 0.1)
				(type default)
			)
			(layer "F.Fab")
		)
		(fp_line
			(start -0.299974 -0.150114)
			(end 0.299974 -0.150114)
			(stroke
				(width 0.1)
				(type default)
			)
			(layer "F.Fab")
		)
		(fp_line
			(start 0.299974 -0.150114)
			(end 0.299974 0.150114)
			(stroke
				(width 0.1)
				(type default)
			)
			(layer "F.Fab")
		)
		(pad "1" smd rect
			(at -0.2667 0 270)
			(size 0.3048 0.381)
			(layers "F.Cu" "F.Mask" "F.Paste")
			(net "P5E_CPU1_PE0_TX_C_DP<15>")
		)
		(pad "2" smd rect
			(at 0.2667 0 270)
			(size 0.3048 0.381)
			(layers "F.Cu" "F.Mask" "F.Paste")
			(net "P5E_CPU1_PE0_TX_DP<15>")
		)
	)
	(footprint ""
		(layer "F.Cu")
		(at 213.54288 -34.508948 180)
		(property "Reference" "R3576"
			(at 0 0 180)
			(layer "F.SilkS")
			(hide yes)
			(effects
				(font
					(size 1.27 1.27)
				)
			)
		)
		(property "Value" ""
			(at 0 0 180)
			(layer "F.Fab")
			(effects
				(font
					(size 1.27 1.27)
				)
			)
		)
		(duplicate_pad_numbers_are_jumpers no)
		(fp_line
			(start 0.7874 0.4064)
			(end -0.7874 0.4064)
			(stroke
				(width 0.1524)
				(type default)
			)
			(layer "F.SilkS")
		)
		(fp_line
			(start 0.7874 -0.4064)
			(end 0.7874 0.4064)
			(stroke
				(width 0.1524)
				(type default)
			)
			(layer "F.SilkS")
		)
		(fp_line
			(start -0.7874 0.4064)
			(end -0.7874 -0.4064)
			(stroke
				(width 0.1524)
				(type default)
			)
			(layer "F.SilkS")
		)
		(fp_line
			(start -0.7874 -0.4064)
			(end 0.7874 -0.4064)
			(stroke
				(width 0.1524)
				(type default)
			)
			(layer "F.SilkS")
		)
		(fp_line
			(start 0.67945 0.3048)
			(end 0.120396 0.3048)
			(stroke
				(width 0.1)
				(type default)
			)
			(layer "F.Fab")
		)
		(fp_line
			(start 0.67945 -0.3048)
			(end 0.67945 0.3048)
			(stroke
				(width 0.1)
				(type default)
			)
			(layer "F.Fab")
		)
		(fp_line
			(start 0.12065 -0.2794)
			(end 0.12065 -0.3048)
			(stroke
				(width 0.1)
				(type default)
			)
			(layer "F.Fab")
		)
		(fp_line
			(start 0.12065 -0.3048)
			(end 0.67945 -0.3048)
			(stroke
				(width 0.1)
				(type default)
			)
			(layer "F.Fab")
		)
		(fp_line
			(start 0.120396 0.3048)
			(end 0.120396 0.2794)
			(stroke
				(width 0.1)
				(type default)
			)
			(layer "F.Fab")
		)
		(fp_line
			(start 0.120396 0.2794)
			(end -0.12065 0.2794)
			(stroke
				(width 0.1)
				(type default)
			)
			(layer "F.Fab")
		)
		(fp_line
			(start -0.12065 0.3048)
			(end -0.67945 0.3048)
			(stroke
				(width 0.1)
				(type default)
			)
			(layer "F.Fab")
		)
		(fp_line
			(start -0.12065 0.2794)
			(end -0.12065 0.3048)
			(stroke
				(width 0.1)
				(type default)
			)
			(layer "F.Fab")
		)
		(fp_line
			(start -0.12065 -0.2794)
			(end 0.12065 -0.2794)
			(stroke
				(width 0.1)
				(type default)
			)
			(layer "F.Fab")
		)
		(fp_line
			(start -0.12065 -0.305054)
			(end -0.12065 -0.2794)
			(stroke
				(width 0.1)
				(type default)
			)
			(layer "F.Fab")
		)
		(fp_line
			(start -0.67945 0.3048)
			(end -0.67945 -0.305054)
			(stroke
				(width 0.1)
				(type default)
			)
			(layer "F.Fab")
		)
		(fp_line
			(start -0.67945 -0.305054)
			(end -0.12065 -0.305054)
			(stroke
				(width 0.1)
				(type default)
			)
			(layer "F.Fab")
		)
		(pad "1" smd circle
			(at -0.40005 0 180)
			(size 0 0)
			(layers "F.Cu" "F.Mask" "F.Paste")
			(net "SMB_INA230_5_3V3AUX_SCL_R")
		)
		(pad "2" smd circle
			(at 0.40005 0 180)
			(size 0 0)
			(layers "F.Cu" "F.Mask" "F.Paste")
			(net "SMB_INA230_5_3V3AUX_SCL_R1")
		)
	)
	(footprint ""
		(layer "F.Cu")
		(at 365.46663 -247.715024 90)
		(property "Reference" "C989"
			(at 0 0 90)
			(layer "F.SilkS")
			(hide yes)
			(effects
				(font
					(size 1.27 1.27)
				)
			)
		)
		(property "Value" ""
			(at 0 0 90)
			(layer "F.Fab")
			(effects
				(font
					(size 1.27 1.27)
				)
			)
		)
		(duplicate_pad_numbers_are_jumpers no)
		(fp_line
			(start 0.7874 -0.4064)
			(end 0.7874 0.4064)
			(stroke
				(width 0.1524)
				(type default)
			)
			(layer "F.SilkS")
		)
		(fp_line
			(start -0.7874 -0.4064)
			(end 0.7874 -0.4064)
			(stroke
				(width 0.1524)
				(type default)
			)
			(layer "F.SilkS")
		)
		(fp_line
			(start 0.7874 0.4064)
			(end -0.7874 0.4064)
			(stroke
				(width 0.1524)
				(type default)
			)
			(layer "F.SilkS")
		)
		(fp_line
			(start -0.7874 0.4064)
			(end -0.7874 -0.4064)
			(stroke
				(width 0.1524)
				(type default)
			)
			(layer "F.SilkS")
		)
		(fp_line
			(start -0.12065 -0.305054)
			(end -0.12065 -0.2794)
			(stroke
				(width 0.1)
				(type default)
			)
			(layer "F.Fab")
		)
		(fp_line
			(start -0.67945 -0.305054)
			(end -0.12065 -0.305054)
			(stroke
				(width 0.1)
				(type default)
			)
			(layer "F.Fab")
		)
		(fp_line
			(start 0.67945 -0.3048)
			(end 0.67945 0.3048)
			(stroke
				(width 0.1)
				(type default)
			)
			(layer "F.Fab")
		)
		(fp_line
			(start 0.12065 -0.3048)
			(end 0.67945 -0.3048)
			(stroke
				(width 0.1)
				(type default)
			)
			(layer "F.Fab")
		)
		(fp_line
			(start 0.12065 -0.2794)
			(end 0.12065 -0.3048)
			(stroke
				(width 0.1)
				(type default)
			)
			(layer "F.Fab")
		)
		(fp_line
			(start -0.12065 -0.2794)
			(end 0.12065 -0.2794)
			(stroke
				(width 0.1)
				(type default)
			)
			(layer "F.Fab")
		)
		(fp_line
			(start 0.120396 0.2794)
			(end -0.12065 0.2794)
			(stroke
				(width 0.1)
				(type default)
			)
			(layer "F.Fab")
		)
		(fp_line
			(start -0.12065 0.2794)
			(end -0.12065 0.3048)
			(stroke
				(width 0.1)
				(type default)
			)
			(layer "F.Fab")
		)
		(fp_line
			(start 0.67945 0.3048)
			(end 0.120396 0.3048)
			(stroke
				(width 0.1)
				(type default)
			)
			(layer "F.Fab")
		)
		(fp_line
			(start 0.120396 0.3048)
			(end 0.120396 0.2794)
			(stroke
				(width 0.1)
				(type default)
			)
			(layer "F.Fab")
		)
		(fp_line
			(start -0.12065 0.3048)
			(end -0.67945 0.3048)
			(stroke
				(width 0.1)
				(type default)
			)
			(layer "F.Fab")
		)
		(fp_line
			(start -0.67945 0.3048)
			(end -0.67945 -0.305054)
			(stroke
				(width 0.1)
				(type default)
			)
			(layer "F.Fab")
		)
		(pad "1" smd circle
			(at -0.40005 0 90)
			(size 0 0)
			(layers "F.Cu" "F.Mask" "F.Paste")
			(net "PVCCIN_CPU0")
		)
		(pad "2" smd circle
			(at 0.40005 0 90)
			(size 0 0)
			(layers "F.Cu" "F.Mask" "F.Paste")
			(net "GND")
		)
	)
)
